(kicad_pcb
	(version 20260206)
	(generator "pcbnew")
	(generator_version "10.0")
	(general
		(thickness 1.6)
		(legacy_teardrops no)
	)
	(paper "A4")
	(title_block
		(title "Bryce Canyon_R.DPB_16317-1_OCP.brd")
		(comment 1 "Bryce Canyon / footprints 750-752 of 2099")
	)
	(layers
		(0 "F.Cu" signal "TOP")
		(4 "In1.Cu" signal "L2GND")
		(6 "In2.Cu" signal "L3")
		(8 "In3.Cu" signal "L4VCC")
		(10 "In4.Cu" signal "L5VCC")
		(12 "In5.Cu" signal "L6")
		(14 "In6.Cu" signal "L7GND")
		(2 "B.Cu" signal "BOTTOM")
		(9 "F.Adhes" user "F.Adhesive")
		(11 "B.Adhes" user "B.Adhesive")
		(13 "F.Paste" user "Package Geometry/Pastemask Top")
		(15 "B.Paste" user "Package Geometry/Pastemask Bottom")
		(5 "F.SilkS" user "Ref Des/Silkscreen Top")
		(7 "B.SilkS" user "Ref Des/Silkscreen Bottom")
		(1 "F.Mask" user "Board Geometry/Soldermask Top")
		(3 "B.Mask" user "Board Geometry/Soldermask Bottom")
		(17 "Dwgs.User" user "User.Drawings")
		(19 "Cmts.User" user "User.Comments")
		(21 "Eco1.User" user "User.Eco1")
		(23 "Eco2.User" user "User.Eco2")
		(25 "Edge.Cuts" user "Board Geometry/Outline")
		(27 "Margin" user)
		(31 "F.CrtYd" user "Package Geometry/Place Bound Top")
		(29 "B.CrtYd" user "Package Geometry/Place Bound Bottom")
		(35 "F.Fab" user "Ref Des/Assembly Top")
		(33 "B.Fab" user "Ref Des/Assembly Bottom")
	)
	(footprint ""
		(layer "F.Cu")
		(at 154.399996 -258.910074 -90)
		(property "Reference" "HDDSAS4"
			(at 0 0 270)
			(layer "F.SilkS")
			(hide yes)
			(effects
				(font
					(size 1.27 1.27)
				)
			)
		)
		(property "Value" "SKT-SAS15P-14P-45-GP"
			(at -20.7645 -8.9789 270)
			(unlocked yes)
			(layer "F.Fab")
			(hide yes)
			(effects
				(font
					(size 1.016 1.016)
					(thickness 0.1524)
				)
			)
		)
		(property "Device Type" "10120818-001C-TRLF"
			(at -20.7645 -10.5029 270)
			(unlocked yes)
			(layer "F.Fab")
			(hide yes)
			(effects
				(font
					(size 1.016 1.016)
					(thickness 0.1524)
				)
			)
		)
		(duplicate_pad_numbers_are_jumpers no)
		(fp_line
			(start 1.651 4.2926)
			(end 1.651 3.0099)
			(stroke
				(width 0.1524)
				(type default)
			)
			(layer "F.SilkS")
		)
		(fp_line
			(start 8.509 4.2926)
			(end 1.651 4.2926)
			(stroke
				(width 0.1524)
				(type default)
			)
			(layer "F.SilkS")
		)
		(fp_line
			(start -23.4188 3.0099)
			(end -23.4188 -3.2512)
			(stroke
				(width 0.1524)
				(type default)
			)
			(layer "F.SilkS")
		)
		(fp_line
			(start 1.651 3.0099)
			(end -23.4188 3.0099)
			(stroke
				(width 0.1524)
				(type default)
			)
			(layer "F.SilkS")
		)
		(fp_line
			(start 8.509 3.0099)
			(end 8.509 4.2926)
			(stroke
				(width 0.1524)
				(type default)
			)
			(layer "F.SilkS")
		)
		(fp_line
			(start 23.4188 3.0099)
			(end 8.509 3.0099)
			(stroke
				(width 0.1524)
				(type default)
			)
			(layer "F.SilkS")
		)
		(fp_line
			(start -23.4188 -3.2512)
			(end 23.4188 -3.2512)
			(stroke
				(width 0.1524)
				(type default)
			)
			(layer "F.SilkS")
		)
		(fp_line
			(start 23.4188 -3.2512)
			(end 23.4188 3.0099)
			(stroke
				(width 0.1524)
				(type default)
			)
			(layer "F.SilkS")
		)
		(fp_line
			(start 15.5067 -3.3401)
			(end 16.2687 -3.3401)
			(stroke
				(width 0.3302)
				(type default)
			)
			(layer "F.SilkS")
		)
		(fp_poly
			(pts
				(xy 15.868904 -3.230372) (xy 16.503904 -3.865372) (xy 15.233904 -3.865372)
			)
			(stroke
				(width 0)
				(type default)
			)
			(fill yes)
			(layer "F.SilkS")
		)
		(fp_poly
			(pts
				(xy -22.8727 -2.7559) (xy 22.8727 -2.7559) (xy 22.8727 2.7559) (xy 8.255 2.7559) (xy 8.255 3.5179)
				(xy 1.905 3.5179) (xy 1.905 2.7559) (xy -22.8727 2.7559)
			)
			(stroke
				(width 0)
				(type default)
			)
			(fill no)
			(layer "F.CrtYd")
		)
		(fp_poly
			(pts
				(xy 1.397 4.5466) (xy 1.397 3.2639) (xy -23.6728 3.2639) (xy -23.6728 -3.5052) (xy 23.6728 -3.5052)
				(xy 23.6728 -0.00635) (xy 22.8727 -0.00635) (xy 22.8727 -2.7559) (xy -22.8727 -2.7559) (xy -22.8727 2.7559)
				(xy 1.905 2.7559) (xy 1.905 3.5179) (xy 8.255 3.5179) (xy 8.255 2.7559) (xy 22.8727 2.7559) (xy 22.8727 0.00635)
				(xy 23.6728 0.00635) (xy 23.6728 3.2639) (xy 8.763 3.2639) (xy 8.763 4.5466)
			)
			(stroke
				(width 0)
				(type default)
			)
			(fill no)
			(layer "F.CrtYd")
		)
		(fp_poly
			(pts
				(xy 1.397 4.5466) (xy 1.397 3.2639) (xy -23.6728 3.2639) (xy -23.6728 -3.5052) (xy 23.6728 -3.5052)
				(xy 23.6728 3.2639) (xy 8.763 3.2639) (xy 8.763 4.5466)
			)
			(stroke
				(width 0)
				(type default)
			)
			(fill no)
			(layer "F.Fab")
		)
		(pad "" np_thru_hole circle
			(at -18.874994 0 270)
			(size 0.254 0.254)
			(drill 1.3462)
			(layers "*.Cu" "*.Mask")
			(clearance 0.9017)
			(thermal_gap 0.9017)
		)
		(pad "" np_thru_hole circle
			(at 18.874994 0 270)
			(size 0.254 0.254)
			(drill 0.9398)
			(layers "*.Cu" "*.Mask")
			(clearance 0.6985)
			(thermal_gap 0.6985)
		)
		(pad "G1" smd rect
			(at 21.874988 0 270)
			(size 2.5908 2.5908)
			(layers "F.Cu" "F.Mask" "F.Paste")
			(net "GND")
		)
		(pad "G2" smd rect
			(at -21.874988 0 270)
			(size 2.5908 2.5908)
			(layers "F.Cu" "F.Mask" "F.Paste")
			(net "GND")
		)
		(pad "P1" smd rect
			(at 1.905 -1.82499 270)
			(size 0.6096 2.3622)
			(layers "F.Cu" "F.Mask" "F.Paste")
			(net "Net_1609")
		)
		(pad "P2" smd rect
			(at 0.635 -1.82499 270)
			(size 0.6096 2.3622)
			(layers "F.Cu" "F.Mask" "F.Paste")
			(net "Net_1610")
		)
		(pad "P3" smd rect
			(at -0.635 -1.82499 270)
			(size 0.6096 2.3622)
			(layers "F.Cu" "F.Mask" "F.Paste")
			(net "Net_1611")
		)
		(pad "P4" smd rect
			(at -1.905 -1.82499 270)
			(size 0.6096 2.3622)
			(layers "F.Cu" "F.Mask" "F.Paste")
			(net "GND")
		)
		(pad "P5" smd rect
			(at -3.175 -1.82499 270)
			(size 0.6096 2.3622)
			(layers "F.Cu" "F.Mask" "F.Paste")
			(net "HDD_PRSNT_4")
		)
		(pad "P6" smd rect
			(at -4.445 -1.82499 270)
			(size 0.6096 2.3622)
			(layers "F.Cu" "F.Mask" "F.Paste")
			(net "GND")
		)
		(pad "P7" smd rect
			(at -5.715 -1.82499 270)
			(size 0.6096 2.3622)
			(layers "F.Cu" "F.Mask" "F.Paste")
			(net "5V_PRE_4")
		)
		(pad "P8" smd rect
			(at -6.985 -1.82499 270)
			(size 0.6096 2.3622)
			(layers "F.Cu" "F.Mask" "F.Paste")
			(net "P5V_HDD4")
		)
		(pad "P9" smd rect
			(at -8.255 -1.82499 270)
			(size 0.6096 2.3622)
			(layers "F.Cu" "F.Mask" "F.Paste")
			(net "P5V_HDD4")
		)
		(pad "P10" smd rect
			(at -9.525 -1.82499 270)
			(size 0.6096 2.3622)
			(layers "F.Cu" "F.Mask" "F.Paste")
			(net "GND")
		)
		(pad "P11" smd rect
			(at -10.795 -1.82499 270)
			(size 0.6096 2.3622)
			(layers "F.Cu" "F.Mask" "F.Paste")
			(net "ACT_HDD_4")
		)
		(pad "P12" smd rect
			(at -12.065 -1.82499 270)
			(size 0.6096 2.3622)
			(layers "F.Cu" "F.Mask" "F.Paste")
			(net "GND")
		)
		(pad "P13" smd rect
			(at -13.335 -1.82499 270)
			(size 0.6096 2.3622)
			(layers "F.Cu" "F.Mask" "F.Paste")
			(net "12V_PRE_4")
		)
		(pad "P14" smd rect
			(at -14.605 -1.82499 270)
			(size 0.6096 2.3622)
			(layers "F.Cu" "F.Mask" "F.Paste")
			(net "P12V_HDD4")
		)
		(pad "P15" smd rect
			(at -15.875 -1.82499 270)
			(size 0.6096 2.3622)
			(layers "F.Cu" "F.Mask" "F.Paste")
			(net "P12V_HDD4")
		)
		(pad "S1" smd rect
			(at 15.875 -1.82499 270)
			(size 0.6096 2.3622)
			(layers "F.Cu" "F.Mask" "F.Paste")
			(net "GND")
		)
		(pad "S2" smd rect
			(at 14.605 -1.82499 270)
			(size 0.6096 2.3622)
			(layers "F.Cu" "F.Mask" "F.Paste")
			(net "SAS_HDD_RX_P4")
		)
		(pad "S3" smd rect
			(at 13.335 -1.82499 270)
			(size 0.6096 2.3622)
			(layers "F.Cu" "F.Mask" "F.Paste")
			(net "SAS_HDD_RX_N4")
		)
		(pad "S4" smd rect
			(at 12.065 -1.82499 270)
			(size 0.6096 2.3622)
			(layers "F.Cu" "F.Mask" "F.Paste")
			(net "GND")
		)
		(pad "S5" smd rect
			(at 10.795 -1.82499 270)
			(size 0.6096 2.3622)
			(layers "F.Cu" "F.Mask" "F.Paste")
			(net "PHY_DRV_B_TO_SCC_B_4_DN")
		)
		(pad "S6" smd rect
			(at 9.525 -1.82499 270)
			(size 0.6096 2.3622)
			(layers "F.Cu" "F.Mask" "F.Paste")
			(net "PHY_DRV_B_TO_SCC_B_4_DP")
		)
		(pad "S7" smd rect
			(at 8.255 -1.82499 270)
			(size 0.6096 2.3622)
			(layers "F.Cu" "F.Mask" "F.Paste")
			(net "GND")
		)
		(pad "S8" smd rect
			(at 7.480046 2.845054 270)
			(size 0.508 2.3622)
			(layers "F.Cu" "F.Mask" "F.Paste")
			(net "GND")
		)
		(pad "S9" smd rect
			(at 6.679946 2.845054 270)
			(size 0.508 2.3622)
			(layers "F.Cu" "F.Mask" "F.Paste")
			(net "Net_462")
		)
		(pad "S10" smd rect
			(at 5.8801 2.845054 270)
			(size 0.508 2.3622)
			(layers "F.Cu" "F.Mask" "F.Paste")
			(net "Net_354")
		)
		(pad "S11" smd rect
			(at 5.08 2.845054 270)
			(size 0.508 2.3622)
			(layers "F.Cu" "F.Mask" "F.Paste")
			(net "GND")
		)
		(pad "S12" smd rect
			(at 4.2799 2.845054 270)
			(size 0.508 2.3622)
			(layers "F.Cu" "F.Mask" "F.Paste")
			(net "Net_390")
		)
		(pad "S13" smd rect
			(at 3.480054 2.845054 270)
			(size 0.508 2.3622)
			(layers "F.Cu" "F.Mask" "F.Paste")
			(net "Net_426")
		)
		(pad "S14" smd rect
			(at 2.679954 2.845054 270)
			(size 0.508 2.3622)
			(layers "F.Cu" "F.Mask" "F.Paste")
			(net "GND")
		)
		(zone
			(layer "F.Cu")
			(hatch none 0.5)
			(connect_pads
				(clearance 0)
			)
			(min_thickness 0.25)
			(keepout
				(tracks not_allowed)
				(vias allowed)
				(pads allowed)
				(copperpour not_allowed)
				(footprints allowed)
			)
			(placement
				(enabled no)
				(sheetname "")
			)
			(fill
				(thermal_gap 0.5)
				(thermal_bridge_width 0.5)
				(island_removal_mode 0)
			)
			(polygon
				(pts
					(xy 158.057596 -275.648674) (xy 150.983696 -275.648674) (xy 150.983696 -282.582874) (xy 152.088596 -282.582874)
					(xy 152.088596 -278.468074) (xy 156.711396 -278.468074) (xy 156.711396 -282.582874) (xy 158.057596 -282.582874)
				)
			)
		)
		(zone
			(layer "F.Cu")
			(hatch none 0.5)
			(connect_pads
				(clearance 0)
			)
			(min_thickness 0.25)
			(keepout
				(tracks allowed)
				(vias not_allowed)
				(pads allowed)
				(copperpour not_allowed)
				(footprints allowed)
			)
			(placement
				(enabled no)
				(sheetname "")
			)
			(fill
				(thermal_gap 0.5)
				(thermal_bridge_width 0.5)
				(island_removal_mode 0)
			)
			(polygon
				(pts
					(xy 158.057596 -275.648674) (xy 150.983696 -275.648674) (xy 150.983696 -282.582874) (xy 152.088596 -282.582874)
					(xy 152.088596 -278.468074) (xy 156.711396 -278.468074) (xy 156.711396 -282.582874) (xy 158.057596 -282.582874)
				)
			)
		)
		(zone
			(layer "F.Cu")
			(hatch none 0.5)
			(connect_pads
				(clearance 0)
			)
			(min_thickness 0.25)
			(keepout
				(tracks allowed)
				(vias not_allowed)
				(pads allowed)
				(copperpour not_allowed)
				(footprints allowed)
			)
			(placement
				(enabled no)
				(sheetname "")
			)
			(fill
				(thermal_gap 0.5)
				(thermal_bridge_width 0.5)
				(island_removal_mode 0)
			)
			(polygon
				(pts
					(xy 158.057596 -242.171474) (xy 150.983696 -242.171474) (xy 150.983696 -235.237274) (xy 152.088596 -235.237274)
					(xy 152.088596 -239.352074) (xy 156.711396 -239.352074) (xy 156.711396 -235.237274) (xy 158.057596 -235.237274)
				)
			)
		)
		(zone
			(layer "F.Cu")
			(hatch none 0.5)
			(connect_pads
				(clearance 0)
			)
			(min_thickness 0.25)
			(keepout
				(tracks not_allowed)
				(vias allowed)
				(pads allowed)
				(copperpour not_allowed)
				(footprints allowed)
			)
			(placement
				(enabled no)
				(sheetname "")
			)
			(fill
				(thermal_gap 0.5)
				(thermal_bridge_width 0.5)
				(island_removal_mode 0)
			)
			(polygon
				(pts
					(xy 158.057596 -242.171474) (xy 150.983696 -242.171474) (xy 150.983696 -235.237274) (xy 152.088596 -235.237274)
					(xy 152.088596 -239.352074) (xy 156.711396 -239.352074) (xy 156.711396 -235.237274) (xy 158.057596 -235.237274)
				)
			)
		)
		(zone
			(layers "F.Cu" "B.Cu" "In1.Cu" "In2.Cu" "In3.Cu" "In4.Cu" "In5.Cu" "In6.Cu")
			(hatch none 0.5)
			(connect_pads
				(clearance 0)
			)
			(min_thickness 0.25)
			(keepout
				(tracks not_allowed)
				(vias allowed)
				(pads allowed)
				(copperpour not_allowed)
				(footprints allowed)
			)
			(placement
				(enabled no)
				(sheetname "")
			)
			(fill
				(thermal_gap 0.5)
				(thermal_bridge_width 0.5)
				(island_removal_mode 0)
			)
			(polygon
				(pts
					(arc
						(start 155.174696 -240.03508)
						(mid 153.625296 -240.03508)
						(end 155.174696 -240.03508)
					)
				)
			)
		)
		(zone
			(layers "F.Cu" "B.Cu" "In1.Cu" "In2.Cu" "In3.Cu" "In4.Cu" "In5.Cu" "In6.Cu")
			(hatch none 0.5)
			(connect_pads
				(clearance 0)
			)
			(min_thickness 0.25)
			(keepout
				(tracks not_allowed)
				(vias allowed)
				(pads allowed)
				(copperpour not_allowed)
				(footprints allowed)
			)
			(placement
				(enabled no)
				(sheetname "")
			)
			(fill
				(thermal_gap 0.5)
				(thermal_bridge_width 0.5)
				(island_removal_mode 0)
			)
			(polygon
				(pts
					(arc
						(start 155.377896 -277.785068)
						(mid 153.422096 -277.785068)
						(end 155.377896 -277.785068)
					)
				)
			)
		)
	)
	(footprint ""
		(layer "F.Cu")
		(at 323.364606 -376.7836 -90)
		(property "Reference" "R1307"
			(at 0 0 270)
			(layer "F.SilkS")
			(hide yes)
			(effects
				(font
					(size 1.27 1.27)
				)
			)
		)
		(property "Value" "4K7R2F-GP"
			(at 0.064008 -3.993896 270)
			(unlocked yes)
			(layer "F.Fab")
			(hide yes)
			(effects
				(font
					(size 1.016 1.016)
					(thickness 0.1524)
				)
			)
		)
		(property "Device Type" "R402H16"
			(at 0.064008 -5.517896 270)
			(unlocked yes)
			(layer "F.Fab")
			(hide yes)
			(effects
				(font
					(size 1.016 1.016)
					(thickness 0.1524)
				)
			)
		)
		(duplicate_pad_numbers_are_jumpers no)
		(fp_line
			(start -0.508 -0.9398)
			(end -0.508 0.9398)
			(stroke
				(width 0.1524)
				(type default)
			)
			(layer "F.SilkS")
		)
		(fp_line
			(start 0.508 -0.9398)
			(end -0.508 -0.9398)
			(stroke
				(width 0.1524)
				(type default)
			)
			(layer "F.SilkS")
		)
		(fp_rect
			(start -0.508 0.9398)
			(end 0.508 -0.9398)
			(stroke
				(width 0)
				(type default)
			)
			(fill no)
			(layer "F.CrtYd")
		)
		(fp_rect
			(start -0.508 0.9398)
			(end 0.508 -0.9398)
			(stroke
				(width 0)
				(type default)
			)
			(fill no)
			(layer "F.Fab")
		)
		(pad "1" smd custom
			(at 0 -0.4445 270)
			(size 0.1397 0.1397)
			(layers "F.Cu" "F.Mask" "F.Paste")
			(net "FAN_YELLOW_LED2")
			(options
				(clearance outline)
				(anchor circle)
			)
			(primitives
				(gr_poly
					(pts
						(arc
							(start -0.1778 -0.2794)
							(mid -0.249642 -0.249642)
							(end -0.2794 -0.1778)
						)
						(arc
							(start -0.2794 0.1778)
							(mid -0.249642 0.249642)
							(end -0.1778 0.2794)
						)
						(arc
							(start 0.1778 0.2794)
							(mid 0.249642 0.249642)
							(end 0.2794 0.1778)
						)
						(arc
							(start 0.2794 -0.1778)
							(mid 0.249642 -0.249642)
							(end 0.1778 -0.2794)
						)
					)
					(width 0)
					(fill yes)
				)
			)
		)
		(pad "2" smd custom
			(at 0 0.4445 270)
			(size 0.1397 0.1397)
			(layers "F.Cu" "F.Mask" "F.Paste")
			(net "FAN_LED2_D2")
			(options
				(clearance outline)
				(anchor circle)
			)
			(primitives
				(gr_poly
					(pts
						(arc
							(start -0.1778 -0.2794)
							(mid -0.249642 -0.249642)
							(end -0.2794 -0.1778)
						)
						(arc
							(start -0.2794 0.1778)
							(mid -0.249642 0.249642)
							(end -0.1778 0.2794)
						)
						(arc
							(start 0.1778 0.2794)
							(mid 0.249642 0.249642)
							(end 0.2794 0.1778)
						)
						(arc
							(start 0.2794 -0.1778)
							(mid 0.249642 -0.249642)
							(end 0.1778 -0.2794)
						)
					)
					(width 0)
					(fill yes)
				)
			)
		)
	)
	(footprint ""
		(layer "F.Cu")
		(at 159.324802 -293.799768)
		(property "Reference" ""
			(at 0 0 0)
			(layer "F.SilkS")
			(hide yes)
			(effects
				(font
					(size 1.27 1.27)
				)
			)
		)
		(property "Value" "*"
			(at -8.398764 -8.057642 0)
			(unlocked yes)
			(layer "F.Fab")
			(hide yes)
			(effects
				(font
					(size 1.016 1.016)
					(thickness 0.1524)
				)
			)
		)
		(duplicate_pad_numbers_are_jumpers no)
		(fp_poly
			(pts
				(arc
					(start 7.3152 0)
					(mid 0 7.3152)
					(end -7.3152 0)
				)
				(arc
					(start -7.3152 -5.9944)
					(mid 0 -13.3096)
					(end 7.3152 -5.9944)
				)
			)
			(stroke
				(width 0)
				(type default)
			)
			(fill no)
			(layer "B.CrtYd")
		)
		(fp_poly
			(pts
				(arc
					(start 7.3152 0)
					(mid 0 7.3152)
					(end -7.3152 0)
				)
				(arc
					(start -7.3152 -5.9944)
					(mid 0 -13.3096)
					(end 7.3152 -5.9944)
				)
			)
			(stroke
				(width 0)
				(type default)
			)
			(fill no)
			(layer "F.CrtYd")
		)
		(fp_poly
			(pts
				(arc
					(start 7.3152 0)
					(mid 0 7.3152)
					(end -7.3152 0)
				)
				(arc
					(start -7.3152 -5.9944)
					(mid 0 -13.3096)
					(end 7.3152 -5.9944)
				)
			)
			(stroke
				(width 0)
				(type default)
			)
			(fill no)
			(layer "B.Fab")
		)
		(fp_poly
			(pts
				(arc
					(start 7.3152 0)
					(mid 0 7.3152)
					(end -7.3152 0)
				)
				(arc
					(start -7.3152 -5.9944)
					(mid 0 -13.3096)
					(end 7.3152 -5.9944)
				)
			)
			(stroke
				(width 0)
				(type default)
			)
			(fill no)
			(layer "F.Fab")
		)
		(pad "1" thru_hole oval
			(at 0 0)
			(size 14.0208 20.0152)
			(drill 0.0254
				(offset 0 -2.9972)
			)
			(layers "*.Cu" "*.Mask")
			(remove_unused_layers no)
			(net "Net_39")
			(clearance -1.002284)
			(thermal_gap 0.1524)
			(padstack
				(mode front_inner_back)
				(layer "Inner"
					(shape custom)
					(size 2.928012 2.928012)
					(options
						(anchor circle)
					)
					(primitives
						(gr_poly
							(pts
								(arc
									(start 4.571746 -2.084324)
									(mid 0.000333 7.430372)
									(end -4.571492 -2.084324)
								)
								(arc
									(start -4.571492 -2.084324)
									(mid -3.570296 -3.611977)
									(end -2.875026 -5.30098)
								)
								(arc
									(start -2.875026 -5.30098)
									(mid 0.000217 -7.43089)
									(end 2.87528 -5.30098)
								)
								(arc
									(start 2.87528 -5.30098)
									(mid 3.570511 -3.611956)
									(end 4.571746 -2.084324)
								)
							)
							(width 0)
							(fill yes)
						)
					)
					(clearance 0.1524)
				)
				(layer "B.Cu"
					(shape oval)
					(size 14.0208 20.0152)
					(offset 0 -2.9972)
					(clearance -1.002284)
				)
			)
		)
		(zone
			(layers "F.Cu" "B.Cu" "In1.Cu" "In2.Cu" "In3.Cu" "In4.Cu" "In5.Cu" "In6.Cu")
			(hatch none 0.5)
			(connect_pads
				(clearance 0)
			)
			(min_thickness 0.25)
			(keepout
				(tracks not_allowed)
				(vias allowed)
				(pads allowed)
				(copperpour not_allowed)
				(footprints allowed)
			)
			(placement
				(enabled no)
				(sheetname "")
			)
			(fill
				(thermal_gap 0.5)
				(thermal_bridge_width 0.5)
				(island_removal_mode 0)
			)
			(polygon
				(pts
					(arc
						(start 152.314402 -299.794168)
						(mid 159.324802 -306.804568)
						(end 166.335202 -299.794168)
					)
					(arc
						(start 166.335202 -293.799768)
						(mid 159.324802 -286.789368)
						(end 152.314402 -293.799768)
					)
				)
			)
		)
	)
)
